# SCM (Grand Teton) — schematic netlist excerpt (pin names and nets, part order shuffled) for the footprints in the layout excerpt that follows; sources: Cadence DE-HDL packaged netlist, KiCad conversion of 12092022_DA0F0TMDCD0_F0T_Management_Board_D_brd_V3_OCP.brd

R545  Q_RES  0 5% CHIP  pkg 0402LF  page 25 : A = GND ; B = FLASH_LATCH_CP
R75  Q_RES  2K 1% CHIP  pkg 0402LF  page 11 : A = P3V3_AUX ; B = SGPIO_DO_1

(kicad_pcb
	(version 20260206)
	(generator "pcbnew")
	(generator_version "10.0")
	(general
		(thickness 1.6)
		(legacy_teardrops no)
	)
	(paper "A4")
	(title_block
		(title "12092022_DA0F0TMDCD0_F0T_Management_Board_D_brd_V3_OCP.brd")
		(comment 1 "Grand Teton / footprints 454-455 of 1440")
	)
	(layers
		(0 "F.Cu" signal "TOP")
		(4 "In1.Cu" signal "GND")
		(6 "In2.Cu" signal "IN1")
		(8 "In3.Cu" signal "GND1")
		(10 "In4.Cu" signal "IN2")
		(12 "In5.Cu" signal "VCC")
		(14 "In6.Cu" signal "VCC1")
		(16 "In7.Cu" signal "IN3")
		(18 "In8.Cu" signal "GND2")
		(20 "In9.Cu" signal "IN4")
		(22 "In10.Cu" signal "GND3")
		(2 "B.Cu" signal "BOTTOM")
		(9 "F.Adhes" user "F.Adhesive")
		(11 "B.Adhes" user "B.Adhesive")
		(13 "F.Paste" user "Package Geometry/Pastemask Top")
		(15 "B.Paste" user "Package Geometry/Pastemask Bottom")
		(5 "F.SilkS" user "Ref Des/Silkscreen Top")
		(7 "B.SilkS" user "Ref Des/Silkscreen Bottom")
		(1 "F.Mask" user "Board Geometry/Soldermask Top")
		(3 "B.Mask" user "Board Geometry/Soldermask Bottom")
		(17 "Dwgs.User" user "User.Drawings")
		(19 "Cmts.User" user "User.Comments")
		(21 "Eco1.User" user "User.Eco1")
		(23 "Eco2.User" user "User.Eco2")
		(25 "Edge.Cuts" user "Board Geometry/Outline")
		(27 "Margin" user)
		(31 "F.CrtYd" user "Package Geometry/Place Bound Top")
		(29 "B.CrtYd" user "Package Geometry/Place Bound Bottom")
		(35 "F.Fab" user "Ref Des/Assembly Top")
		(33 "B.Fab" user "Ref Des/Assembly Bottom")
	)
	(footprint ""
		(layer "F.Cu")
		(at 40.0304 -109.474 -90)
		(property "Reference" "R75"
			(at 0 0 270)
			(layer "F.SilkS")
			(hide yes)
			(effects
				(font
					(size 1.27 1.27)
				)
			)
		)
		(property "Value" ""
			(at 0 0 270)
			(layer "F.Fab")
			(effects
				(font
					(size 1.27 1.27)
				)
			)
		)
		(duplicate_pad_numbers_are_jumpers no)
		(fp_line
			(start -0.7874 0.4064)
			(end -0.7874 -0.4064)
			(stroke
				(width 0.1524)
				(type default)
			)
			(layer "F.SilkS")
		)
		(fp_line
			(start 0.7874 0.4064)
			(end -0.7874 0.4064)
			(stroke
				(width 0.1524)
				(type default)
			)
			(layer "F.SilkS")
		)
		(fp_line
			(start -0.7874 -0.4064)
			(end 0.7874 -0.4064)
			(stroke
				(width 0.1524)
				(type default)
			)
			(layer "F.SilkS")
		)
		(fp_line
			(start 0.7874 -0.4064)
			(end 0.7874 0.4064)
			(stroke
				(width 0.1524)
				(type default)
			)
			(layer "F.SilkS")
		)
		(fp_line
			(start -0.67945 0.3048)
			(end -0.67945 -0.305054)
			(stroke
				(width 0.1)
				(type default)
			)
			(layer "F.Fab")
		)
		(fp_line
			(start -0.12065 0.3048)
			(end -0.67945 0.3048)
			(stroke
				(width 0.1)
				(type default)
			)
			(layer "F.Fab")
		)
		(fp_line
			(start 0.120396 0.3048)
			(end 0.120396 0.2794)
			(stroke
				(width 0.1)
				(type default)
			)
			(layer "F.Fab")
		)
		(fp_line
			(start 0.67945 0.3048)
			(end 0.120396 0.3048)
			(stroke
				(width 0.1)
				(type default)
			)
			(layer "F.Fab")
		)
		(fp_line
			(start -0.12065 0.2794)
			(end -0.12065 0.3048)
			(stroke
				(width 0.1)
				(type default)
			)
			(layer "F.Fab")
		)
		(fp_line
			(start 0.120396 0.2794)
			(end -0.12065 0.2794)
			(stroke
				(width 0.1)
				(type default)
			)
			(layer "F.Fab")
		)
		(fp_line
			(start -0.12065 -0.2794)
			(end 0.12065 -0.2794)
			(stroke
				(width 0.1)
				(type default)
			)
			(layer "F.Fab")
		)
		(fp_line
			(start 0.12065 -0.2794)
			(end 0.12065 -0.3048)
			(stroke
				(width 0.1)
				(type default)
			)
			(layer "F.Fab")
		)
		(fp_line
			(start 0.12065 -0.3048)
			(end 0.67945 -0.3048)
			(stroke
				(width 0.1)
				(type default)
			)
			(layer "F.Fab")
		)
		(fp_line
			(start 0.67945 -0.3048)
			(end 0.67945 0.3048)
			(stroke
				(width 0.1)
				(type default)
			)
			(layer "F.Fab")
		)
		(fp_line
			(start -0.67945 -0.305054)
			(end -0.12065 -0.305054)
			(stroke
				(width 0.1)
				(type default)
			)
			(layer "F.Fab")
		)
		(fp_line
			(start -0.12065 -0.305054)
			(end -0.12065 -0.2794)
			(stroke
				(width 0.1)
				(type default)
			)
			(layer "F.Fab")
		)
		(pad "1" smd circle
			(at -0.40005 0 270)
			(size 0 0)
			(layers "F.Cu" "F.Mask" "F.Paste")
			(net "P3V3_AUX")
		)
		(pad "2" smd circle
			(at 0.40005 0 270)
			(size 0 0)
			(layers "F.Cu" "F.Mask" "F.Paste")
			(net "SGPIO_DO_1")
		)
	)
	(footprint ""
		(layer "F.Cu")
		(at 57.023 -75.3364 180)
		(property "Reference" "R545"
			(at 0 0 180)
			(layer "F.SilkS")
			(hide yes)
			(effects
				(font
					(size 1.27 1.27)
				)
			)
		)
		(property "Value" ""
			(at 0 0 180)
			(layer "F.Fab")
			(effects
				(font
					(size 1.27 1.27)
				)
			)
		)
		(duplicate_pad_numbers_are_jumpers no)
		(fp_line
			(start 0.7874 0.4064)
			(end -0.7874 0.4064)
			(stroke
				(width 0.1524)
				(type default)
			)
			(layer "F.SilkS")
		)
		(fp_line
			(start 0.7874 -0.4064)
			(end 0.7874 0.4064)
			(stroke
				(width 0.1524)
				(type default)
			)
			(layer "F.SilkS")
		)
		(fp_line
			(start -0.7874 0.4064)
			(end -0.7874 -0.4064)
			(stroke
				(width 0.1524)
				(type default)
			)
			(layer "F.SilkS")
		)
		(fp_line
			(start -0.7874 -0.4064)
			(end 0.7874 -0.4064)
			(stroke
				(width 0.1524)
				(type default)
			)
			(layer "F.SilkS")
		)
		(fp_line
			(start 0.67945 0.3048)
			(end 0.120396 0.3048)
			(stroke
				(width 0.1)
				(type default)
			)
			(layer "F.Fab")
		)
		(fp_line
			(start 0.67945 -0.3048)
			(end 0.67945 0.3048)
			(stroke
				(width 0.1)
				(type default)
			)
			(layer "F.Fab")
		)
		(fp_line
			(start 0.12065 -0.2794)
			(end 0.12065 -0.3048)
			(stroke
				(width 0.1)
				(type default)
			)
			(layer "F.Fab")
		)
		(fp_line
			(start 0.12065 -0.3048)
			(end 0.67945 -0.3048)
			(stroke
				(width 0.1)
				(type default)
			)
			(layer "F.Fab")
		)
		(fp_line
			(start 0.120396 0.3048)
			(end 0.120396 0.2794)
			(stroke
				(width 0.1)
				(type default)
			)
			(layer "F.Fab")
		)
		(fp_line
			(start 0.120396 0.2794)
			(end -0.12065 0.2794)
			(stroke
				(width 0.1)
				(type default)
			)
			(layer "F.Fab")
		)
		(fp_line
			(start -0.12065 0.3048)
			(end -0.67945 0.3048)
			(stroke
				(width 0.1)
				(type default)
			)
			(layer "F.Fab")
		)
		(fp_line
			(start -0.12065 0.2794)
			(end -0.12065 0.3048)
			(stroke
				(width 0.1)
				(type default)
			)
			(layer "F.Fab")
		)
		(fp_line
			(start -0.12065 -0.2794)
			(end 0.12065 -0.2794)
			(stroke
				(width 0.1)
				(type default)
			)
			(layer "F.Fab")
		)
		(fp_line
			(start -0.12065 -0.305054)
			(end -0.12065 -0.2794)
			(stroke
				(width 0.1)
				(type default)
			)
			(layer "F.Fab")
		)
		(fp_line
			(start -0.67945 0.3048)
			(end -0.67945 -0.305054)
			(stroke
				(width 0.1)
				(type default)
			)
			(layer "F.Fab")
		)
		(fp_line
			(start -0.67945 -0.305054)
			(end -0.12065 -0.305054)
			(stroke
				(width 0.1)
				(type default)
			)
			(layer "F.Fab")
		)
		(pad "1" smd circle
			(at -0.40005 0 180)
			(size 0 0)
			(layers "F.Cu" "F.Mask" "F.Paste")
			(net "GND")
		)
		(pad "2" smd circle
			(at 0.40005 0 180)
			(size 0 0)
			(layers "F.Cu" "F.Mask" "F.Paste")
			(net "FLASH_LATCH_CP")
		)
	)
)
